# T6G (Grand Teton) — schematic netlist excerpt (pin names and nets, part order shuffled) for the footprints in the layout excerpt that follows; sources: Cadence DE-HDL packaged netlist, KiCad conversion of 04192023_DAF0TMB3IC0_F0TG_MB_C_brd_V02_OCP.brd

C249  Q_CAP  1000PF 50V 5% X7R  pkg 0402  page 210 : A = PVDDCR_CPU0_P1_EN_R ; B = GND
C226  Q_CAP  0.1UF 25V 10% X7R  pkg 0402  page 34 : A = PVDD18_S5_P0 ; B = GND

(kicad_pcb
	(version 20260206)
	(generator "pcbnew")
	(generator_version "10.0")
	(general
		(thickness 1.6)
		(legacy_teardrops no)
	)
	(paper "A4")
	(title_block
		(title "04192023_DAF0TMB3IC0_F0TG_MB_C_brd_V02_OCP.brd")
		(comment 1 "Grand Teton / footprints 6356-6357 of 8354")
	)
	(layers
		(0 "F.Cu" signal "TOP")
		(4 "In1.Cu" signal "GND")
		(6 "In2.Cu" signal "IN1")
		(8 "In3.Cu" signal "GND1")
		(10 "In4.Cu" signal "IN2")
		(12 "In5.Cu" signal "GND2")
		(14 "In6.Cu" signal "IN3")
		(16 "In7.Cu" signal "GND3")
		(18 "In8.Cu" signal "VCC")
		(20 "In9.Cu" signal "VCC1")
		(22 "In10.Cu" signal "GND4")
		(24 "In11.Cu" signal "IN4")
		(26 "In12.Cu" signal "GND5")
		(28 "In13.Cu" signal "IN5")
		(30 "In14.Cu" signal "GND6")
		(32 "In15.Cu" signal "IN6")
		(34 "In16.Cu" signal "GND7")
		(2 "B.Cu" signal "BOTTOM")
		(9 "F.Adhes" user "F.Adhesive")
		(11 "B.Adhes" user "B.Adhesive")
		(13 "F.Paste" user "Package Geometry/Pastemask Top")
		(15 "B.Paste" user "Package Geometry/Pastemask Bottom")
		(5 "F.SilkS" user "Ref Des/Silkscreen Top")
		(7 "B.SilkS" user "Ref Des/Silkscreen Bottom")
		(1 "F.Mask" user "Board Geometry/Soldermask Top")
		(3 "B.Mask" user "Board Geometry/Soldermask Bottom")
		(17 "Dwgs.User" user "User.Drawings")
		(19 "Cmts.User" user "User.Comments")
		(21 "Eco1.User" user "User.Eco1")
		(23 "Eco2.User" user "User.Eco2")
		(25 "Edge.Cuts" user "Board Geometry/Outline")
		(27 "Margin" user)
		(31 "F.CrtYd" user "Package Geometry/Place Bound Top")
		(29 "B.CrtYd" user "Package Geometry/Place Bound Bottom")
		(35 "F.Fab" user "Ref Des/Assembly Top")
		(33 "B.Fab" user "Ref Des/Assembly Bottom")
	)
	(footprint ""
		(layer "B.Cu")
		(at 401.554696 -344.850212 90)
		(property "Reference" "C226"
			(at 0 0 90)
			(layer "B.SilkS")
			(hide yes)
			(effects
				(font
					(size 1.27 1.27)
				)
				(justify mirror)
			)
		)
		(property "Value" ""
			(at 0 0 90)
			(layer "B.Fab")
			(effects
				(font
					(size 1.27 1.27)
				)
				(justify mirror)
			)
		)
		(duplicate_pad_numbers_are_jumpers no)
		(fp_line
			(start 0.7874 -0.4064)
			(end -0.7874 -0.4064)
			(stroke
				(width 0.1524)
				(type default)
			)
			(layer "B.SilkS")
		)
		(fp_line
			(start -0.7874 -0.4064)
			(end -0.7874 0.4064)
			(stroke
				(width 0.1524)
				(type default)
			)
			(layer "B.SilkS")
		)
		(fp_line
			(start 0.7874 0.4064)
			(end 0.7874 -0.4064)
			(stroke
				(width 0.1524)
				(type default)
			)
			(layer "B.SilkS")
		)
		(fp_line
			(start -0.7874 0.4064)
			(end 0.7874 0.4064)
			(stroke
				(width 0.1524)
				(type default)
			)
			(layer "B.SilkS")
		)
		(fp_line
			(start 0.67945 -0.305054)
			(end 0.12065 -0.305054)
			(stroke
				(width 0.1)
				(type default)
			)
			(layer "B.Fab")
		)
		(fp_line
			(start 0.12065 -0.305054)
			(end 0.12065 -0.2794)
			(stroke
				(width 0.1)
				(type default)
			)
			(layer "B.Fab")
		)
		(fp_line
			(start -0.12065 -0.3048)
			(end -0.67945 -0.3048)
			(stroke
				(width 0.1)
				(type default)
			)
			(layer "B.Fab")
		)
		(fp_line
			(start -0.67945 -0.3048)
			(end -0.67945 0.3048)
			(stroke
				(width 0.1)
				(type default)
			)
			(layer "B.Fab")
		)
		(fp_line
			(start 0.12065 -0.2794)
			(end -0.12065 -0.2794)
			(stroke
				(width 0.1)
				(type default)
			)
			(layer "B.Fab")
		)
		(fp_line
			(start -0.12065 -0.2794)
			(end -0.12065 -0.3048)
			(stroke
				(width 0.1)
				(type default)
			)
			(layer "B.Fab")
		)
		(fp_line
			(start 0.12065 0.2794)
			(end 0.12065 0.3048)
			(stroke
				(width 0.1)
				(type default)
			)
			(layer "B.Fab")
		)
		(fp_line
			(start -0.120396 0.2794)
			(end 0.12065 0.2794)
			(stroke
				(width 0.1)
				(type default)
			)
			(layer "B.Fab")
		)
		(fp_line
			(start 0.67945 0.3048)
			(end 0.67945 -0.305054)
			(stroke
				(width 0.1)
				(type default)
			)
			(layer "B.Fab")
		)
		(fp_line
			(start 0.12065 0.3048)
			(end 0.67945 0.3048)
			(stroke
				(width 0.1)
				(type default)
			)
			(layer "B.Fab")
		)
		(fp_line
			(start -0.120396 0.3048)
			(end -0.120396 0.2794)
			(stroke
				(width 0.1)
				(type default)
			)
			(layer "B.Fab")
		)
		(fp_line
			(start -0.67945 0.3048)
			(end -0.120396 0.3048)
			(stroke
				(width 0.1)
				(type default)
			)
			(layer "B.Fab")
		)
		(pad "1" smd circle
			(at 0.40005 0 270)
			(size 0 0)
			(layers "B.Cu" "B.Mask" "B.Paste")
			(net "PVDD18_S5_P0")
		)
		(pad "2" smd circle
			(at -0.40005 0 270)
			(size 0 0)
			(layers "B.Cu" "B.Mask" "B.Paste")
			(net "GND")
		)
	)
	(footprint ""
		(layer "B.Cu")
		(at 90.209878 -142.85341)
		(property "Reference" "C249"
			(at 0 0 0)
			(layer "B.SilkS")
			(hide yes)
			(effects
				(font
					(size 1.27 1.27)
				)
				(justify mirror)
			)
		)
		(property "Value" ""
			(at 0 0 0)
			(layer "B.Fab")
			(effects
				(font
					(size 1.27 1.27)
				)
				(justify mirror)
			)
		)
		(duplicate_pad_numbers_are_jumpers no)
		(fp_line
			(start -0.7874 -0.4064)
			(end -0.7874 0.4064)
			(stroke
				(width 0.1524)
				(type default)
			)
			(layer "B.SilkS")
		)
		(fp_line
			(start -0.7874 0.4064)
			(end 0.7874 0.4064)
			(stroke
				(width 0.1524)
				(type default)
			)
			(layer "B.SilkS")
		)
		(fp_line
			(start 0.7874 -0.4064)
			(end -0.7874 -0.4064)
			(stroke
				(width 0.1524)
				(type default)
			)
			(layer "B.SilkS")
		)
		(fp_line
			(start 0.7874 0.4064)
			(end 0.7874 -0.4064)
			(stroke
				(width 0.1524)
				(type default)
			)
			(layer "B.SilkS")
		)
		(fp_line
			(start -0.67945 -0.3048)
			(end -0.67945 0.3048)
			(stroke
				(width 0.1)
				(type default)
			)
			(layer "B.Fab")
		)
		(fp_line
			(start -0.67945 0.3048)
			(end -0.120396 0.3048)
			(stroke
				(width 0.1)
				(type default)
			)
			(layer "B.Fab")
		)
		(fp_line
			(start -0.12065 -0.3048)
			(end -0.67945 -0.3048)
			(stroke
				(width 0.1)
				(type default)
			)
			(layer "B.Fab")
		)
		(fp_line
			(start -0.12065 -0.2794)
			(end -0.12065 -0.3048)
			(stroke
				(width 0.1)
				(type default)
			)
			(layer "B.Fab")
		)
		(fp_line
			(start -0.120396 0.2794)
			(end 0.12065 0.2794)
			(stroke
				(width 0.1)
				(type default)
			)
			(layer "B.Fab")
		)
		(fp_line
			(start -0.120396 0.3048)
			(end -0.120396 0.2794)
			(stroke
				(width 0.1)
				(type default)
			)
			(layer "B.Fab")
		)
		(fp_line
			(start 0.12065 -0.305054)
			(end 0.12065 -0.2794)
			(stroke
				(width 0.1)
				(type default)
			)
			(layer "B.Fab")
		)
		(fp_line
			(start 0.12065 -0.2794)
			(end -0.12065 -0.2794)
			(stroke
				(width 0.1)
				(type default)
			)
			(layer "B.Fab")
		)
		(fp_line
			(start 0.12065 0.2794)
			(end 0.12065 0.3048)
			(stroke
				(width 0.1)
				(type default)
			)
			(layer "B.Fab")
		)
		(fp_line
			(start 0.12065 0.3048)
			(end 0.67945 0.3048)
			(stroke
				(width 0.1)
				(type default)
			)
			(layer "B.Fab")
		)
		(fp_line
			(start 0.67945 -0.305054)
			(end 0.12065 -0.305054)
			(stroke
				(width 0.1)
				(type default)
			)
			(layer "B.Fab")
		)
		(fp_line
			(start 0.67945 0.3048)
			(end 0.67945 -0.305054)
			(stroke
				(width 0.1)
				(type default)
			)
			(layer "B.Fab")
		)
		(pad "1" smd circle
			(at 0.40005 0 180)
			(size 0 0)
			(layers "B.Cu" "B.Mask" "B.Paste")
			(net "PVDDCR_CPU0_P1_EN_R")
		)
		(pad "2" smd circle
			(at -0.40005 0 180)
			(size 0 0)
			(layers "B.Cu" "B.Mask" "B.Paste")
			(net "GND")
		)
	)
)
